# S9S_MB_2U (Grand Teton) — schematic netlist excerpt (pin names and nets, part order shuffled) for the footprints in the layout excerpt that follows; sources: Cadence DE-HDL packaged netlist, KiCad conversion of 03242023_DA0F0TMBIJ0_F0T_Motherboard_J_brd_V01_OCP.brd

C862  Q_CAP_DIFFBUS  DIFF BUS_0.22UF 6.3V 20% X6S  pkg C0201  page 174 : \1\ = P5E_CPU0_PE1_TX_C_DN<3> ; \2\ = P5E_CPU0_PE1_TX_DN<3>
C1859  Q_CAP  0.1UF 25V 10% X7R  pkg 0402  page 238 : A = P3V3_AUX ; B = GND
PC1363  Q_CAP  0.1UF 25V 10% X7R  pkg 0402  page 288 : A = GND ; B = PVCCIN_CPU1_VREF

(kicad_pcb
	(version 20260206)
	(generator "pcbnew")
	(generator_version "10.0")
	(general
		(thickness 1.6)
		(legacy_teardrops no)
	)
	(paper "A4")
	(title_block
		(title "03242023_DA0F0TMBIJ0_F0T_Motherboard_J_brd_V01_OCP.brd")
		(comment 1 "Grand Teton / footprints 2438-2440 of 6105")
	)
	(layers
		(0 "F.Cu" signal "TOP")
		(4 "In1.Cu" signal "GND")
		(6 "In2.Cu" signal "IN1")
		(8 "In3.Cu" signal "GND1")
		(10 "In4.Cu" signal "IN2")
		(12 "In5.Cu" signal "GND2")
		(14 "In6.Cu" signal "IN3")
		(16 "In7.Cu" signal "GND3")
		(18 "In8.Cu" signal "VCC")
		(20 "In9.Cu" signal "VCC1")
		(22 "In10.Cu" signal "GND4")
		(24 "In11.Cu" signal "IN4")
		(26 "In12.Cu" signal "GND5")
		(28 "In13.Cu" signal "IN5")
		(30 "In14.Cu" signal "GND6")
		(32 "In15.Cu" signal "IN6")
		(34 "In16.Cu" signal "GND7")
		(2 "B.Cu" signal "BOTTOM")
		(9 "F.Adhes" user "F.Adhesive")
		(11 "B.Adhes" user "B.Adhesive")
		(13 "F.Paste" user "Package Geometry/Pastemask Top")
		(15 "B.Paste" user "Package Geometry/Pastemask Bottom")
		(5 "F.SilkS" user "Ref Des/Silkscreen Top")
		(7 "B.SilkS" user "Ref Des/Silkscreen Bottom")
		(1 "F.Mask" user "Board Geometry/Soldermask Top")
		(3 "B.Mask" user "Board Geometry/Soldermask Bottom")
		(17 "Dwgs.User" user "User.Drawings")
		(19 "Cmts.User" user "User.Comments")
		(21 "Eco1.User" user "User.Eco1")
		(23 "Eco2.User" user "User.Eco2")
		(25 "Edge.Cuts" user "Board Geometry/Outline")
		(27 "Margin" user)
		(31 "F.CrtYd" user "Package Geometry/Place Bound Top")
		(29 "B.CrtYd" user "Package Geometry/Place Bound Bottom")
		(35 "F.Fab" user "Ref Des/Assembly Top")
		(33 "B.Fab" user "Ref Des/Assembly Bottom")
	)
	(footprint ""
		(layer "F.Cu")
		(at 107.96905 -29.842714)
		(property "Reference" "C1859"
			(at 0 0 0)
			(layer "F.SilkS")
			(hide yes)
			(effects
				(font
					(size 1.27 1.27)
				)
			)
		)
		(property "Value" ""
			(at 0 0 0)
			(layer "F.Fab")
			(effects
				(font
					(size 1.27 1.27)
				)
			)
		)
		(duplicate_pad_numbers_are_jumpers no)
		(fp_line
			(start -0.7874 -0.4064)
			(end 0.7874 -0.4064)
			(stroke
				(width 0.1524)
				(type default)
			)
			(layer "F.SilkS")
		)
		(fp_line
			(start -0.7874 0.4064)
			(end -0.7874 -0.4064)
			(stroke
				(width 0.1524)
				(type default)
			)
			(layer "F.SilkS")
		)
		(fp_line
			(start 0.7874 -0.4064)
			(end 0.7874 0.4064)
			(stroke
				(width 0.1524)
				(type default)
			)
			(layer "F.SilkS")
		)
		(fp_line
			(start 0.7874 0.4064)
			(end -0.7874 0.4064)
			(stroke
				(width 0.1524)
				(type default)
			)
			(layer "F.SilkS")
		)
		(fp_line
			(start -0.67945 -0.305054)
			(end -0.12065 -0.305054)
			(stroke
				(width 0.1)
				(type default)
			)
			(layer "F.Fab")
		)
		(fp_line
			(start -0.67945 0.3048)
			(end -0.67945 -0.305054)
			(stroke
				(width 0.1)
				(type default)
			)
			(layer "F.Fab")
		)
		(fp_line
			(start -0.12065 -0.305054)
			(end -0.12065 -0.2794)
			(stroke
				(width 0.1)
				(type default)
			)
			(layer "F.Fab")
		)
		(fp_line
			(start -0.12065 -0.2794)
			(end 0.12065 -0.2794)
			(stroke
				(width 0.1)
				(type default)
			)
			(layer "F.Fab")
		)
		(fp_line
			(start -0.12065 0.2794)
			(end -0.12065 0.3048)
			(stroke
				(width 0.1)
				(type default)
			)
			(layer "F.Fab")
		)
		(fp_line
			(start -0.12065 0.3048)
			(end -0.67945 0.3048)
			(stroke
				(width 0.1)
				(type default)
			)
			(layer "F.Fab")
		)
		(fp_line
			(start 0.120396 0.2794)
			(end -0.12065 0.2794)
			(stroke
				(width 0.1)
				(type default)
			)
			(layer "F.Fab")
		)
		(fp_line
			(start 0.120396 0.3048)
			(end 0.120396 0.2794)
			(stroke
				(width 0.1)
				(type default)
			)
			(layer "F.Fab")
		)
		(fp_line
			(start 0.12065 -0.3048)
			(end 0.67945 -0.3048)
			(stroke
				(width 0.1)
				(type default)
			)
			(layer "F.Fab")
		)
		(fp_line
			(start 0.12065 -0.2794)
			(end 0.12065 -0.3048)
			(stroke
				(width 0.1)
				(type default)
			)
			(layer "F.Fab")
		)
		(fp_line
			(start 0.67945 -0.3048)
			(end 0.67945 0.3048)
			(stroke
				(width 0.1)
				(type default)
			)
			(layer "F.Fab")
		)
		(fp_line
			(start 0.67945 0.3048)
			(end 0.120396 0.3048)
			(stroke
				(width 0.1)
				(type default)
			)
			(layer "F.Fab")
		)
		(pad "1" smd circle
			(at -0.40005 0)
			(size 0 0)
			(layers "F.Cu" "F.Mask" "F.Paste")
			(net "P3V3_AUX")
		)
		(pad "2" smd circle
			(at 0.40005 0)
			(size 0 0)
			(layers "F.Cu" "F.Mask" "F.Paste")
			(net "GND")
		)
	)
	(footprint ""
		(layer "F.Cu")
		(at 424.7642 -16.088614 90)
		(property "Reference" "C862"
			(at 0 0 90)
			(layer "F.SilkS")
			(hide yes)
			(effects
				(font
					(size 1.27 1.27)
				)
			)
		)
		(property "Value" ""
			(at 0 0 90)
			(layer "F.Fab")
			(effects
				(font
					(size 1.27 1.27)
				)
			)
		)
		(duplicate_pad_numbers_are_jumpers no)
		(fp_line
			(start 0.299974 -0.150114)
			(end 0.299974 0.150114)
			(stroke
				(width 0.1)
				(type default)
			)
			(layer "F.Fab")
		)
		(fp_line
			(start -0.299974 -0.150114)
			(end 0.299974 -0.150114)
			(stroke
				(width 0.1)
				(type default)
			)
			(layer "F.Fab")
		)
		(fp_line
			(start 0.299974 0.150114)
			(end -0.299974 0.150114)
			(stroke
				(width 0.1)
				(type default)
			)
			(layer "F.Fab")
		)
		(fp_line
			(start -0.299974 0.150114)
			(end -0.299974 -0.150114)
			(stroke
				(width 0.1)
				(type default)
			)
			(layer "F.Fab")
		)
		(pad "1" smd rect
			(at -0.2667 0 90)
			(size 0.3048 0.381)
			(layers "F.Cu" "F.Mask" "F.Paste")
			(net "P5E_CPU0_PE1_TX_C_DN<3>")
		)
		(pad "2" smd rect
			(at 0.2667 0 90)
			(size 0.3048 0.381)
			(layers "F.Cu" "F.Mask" "F.Paste")
			(net "P5E_CPU0_PE1_TX_DN<3>")
		)
	)
	(footprint ""
		(layer "F.Cu")
		(at 77.982826 -347.481398 -90)
		(property "Reference" "PC1363"
			(at 0 0 270)
			(layer "F.SilkS")
			(hide yes)
			(effects
				(font
					(size 1.27 1.27)
				)
			)
		)
		(property "Value" ""
			(at 0 0 270)
			(layer "F.Fab")
			(effects
				(font
					(size 1.27 1.27)
				)
			)
		)
		(duplicate_pad_numbers_are_jumpers no)
		(fp_line
			(start -0.7874 0.4064)
			(end -0.7874 -0.4064)
			(stroke
				(width 0.1524)
				(type default)
			)
			(layer "F.SilkS")
		)
		(fp_line
			(start 0.7874 0.4064)
			(end -0.7874 0.4064)
			(stroke
				(width 0.1524)
				(type default)
			)
			(layer "F.SilkS")
		)
		(fp_line
			(start -0.7874 -0.4064)
			(end 0.7874 -0.4064)
			(stroke
				(width 0.1524)
				(type default)
			)
			(layer "F.SilkS")
		)
		(fp_line
			(start 0.7874 -0.4064)
			(end 0.7874 0.4064)
			(stroke
				(width 0.1524)
				(type default)
			)
			(layer "F.SilkS")
		)
		(fp_line
			(start -0.67945 0.3048)
			(end -0.67945 -0.305054)
			(stroke
				(width 0.1)
				(type default)
			)
			(layer "F.Fab")
		)
		(fp_line
			(start -0.12065 0.3048)
			(end -0.67945 0.3048)
			(stroke
				(width 0.1)
				(type default)
			)
			(layer "F.Fab")
		)
		(fp_line
			(start 0.120396 0.3048)
			(end 0.120396 0.2794)
			(stroke
				(width 0.1)
				(type default)
			)
			(layer "F.Fab")
		)
		(fp_line
			(start 0.67945 0.3048)
			(end 0.120396 0.3048)
			(stroke
				(width 0.1)
				(type default)
			)
			(layer "F.Fab")
		)
		(fp_line
			(start -0.12065 0.2794)
			(end -0.12065 0.3048)
			(stroke
				(width 0.1)
				(type default)
			)
			(layer "F.Fab")
		)
		(fp_line
			(start 0.120396 0.2794)
			(end -0.12065 0.2794)
			(stroke
				(width 0.1)
				(type default)
			)
			(layer "F.Fab")
		)
		(fp_line
			(start -0.12065 -0.2794)
			(end 0.12065 -0.2794)
			(stroke
				(width 0.1)
				(type default)
			)
			(layer "F.Fab")
		)
		(fp_line
			(start 0.12065 -0.2794)
			(end 0.12065 -0.3048)
			(stroke
				(width 0.1)
				(type default)
			)
			(layer "F.Fab")
		)
		(fp_line
			(start 0.12065 -0.3048)
			(end 0.67945 -0.3048)
			(stroke
				(width 0.1)
				(type default)
			)
			(layer "F.Fab")
		)
		(fp_line
			(start 0.67945 -0.3048)
			(end 0.67945 0.3048)
			(stroke
				(width 0.1)
				(type default)
			)
			(layer "F.Fab")
		)
		(fp_line
			(start -0.67945 -0.305054)
			(end -0.12065 -0.305054)
			(stroke
				(width 0.1)
				(type default)
			)
			(layer "F.Fab")
		)
		(fp_line
			(start -0.12065 -0.305054)
			(end -0.12065 -0.2794)
			(stroke
				(width 0.1)
				(type default)
			)
			(layer "F.Fab")
		)
		(pad "1" smd circle
			(at -0.40005 0 270)
			(size 0 0)
			(layers "F.Cu" "F.Mask" "F.Paste")
			(net "GND")
		)
		(pad "2" smd circle
			(at 0.40005 0 270)
			(size 0 0)
			(layers "F.Cu" "F.Mask" "F.Paste")
			(net "PVCCIN_CPU1_VREF")
		)
	)
)
